FILE_TYPE = CONNECTIVITY;
{Allegro Design Entry HDL 17.4-2019 S026 (4007227) 1/17/2022}
"PAGE_NUMBER" = 172;
0"NC";
END.
